FILE_TYPE = MACRO_DRAWING;
SET COLOR_WIRE YELLOW;
SET COLOR_PROP MONO;
SET COLOR_DOT WHITE;
SET COLOR_ARC YELLOW;
SET COLOR_BODY GREEN;
SET COLOR_NOTE MONO;
SET PROP_DISPLAY VALUE;
SET PAGE_NUMBER P91;
FORCEADD SCONN24_H46321001..1
(25 2825);
FORCEPROP 1 LAST LOCATION J8B1
J 0
(-325 3375);
DISPLAY 0.617021 (-325 3375);
PAINT AQUA (-325 3375);
FORCEPROP 1 LAST PART_NUMBER H46321-001
J 0
(-325 2325);
DISPLAY 0.617021 (-325 2325);
PAINT BLUE (-325 2325);
FORCEPROP 1 LAST MATERIAL SCONN
J 0
(-325 3325);
DISPLAY 0.617021 (-325 3325);
PAINT SKYBLUE (-325 3325);
FORCEPROP 2 LASTPIN (425 2475) $PN MP2
J 0
(435 2485);
DISPLAY 0.617021 (435 2485);
PAINT MONO (435 2485);
FORCEPROP 2 LASTPIN (-375 2475) $PN MP1
J 2
(-360 2485);
DISPLAY 0.617021 (-360 2485);
PAINT MONO (-360 2485);
FORCEPROP 2 LASTPIN (425 2575) $PN 24
J 0
(435 2585);
DISPLAY 0.617021 (435 2585);
PAINT MONO (435 2585);
FORCEPROP 2 LASTPIN (-375 2575) $PN 23
J 2
(-385 2585);
DISPLAY 0.617021 (-385 2585);
PAINT MONO (-385 2585);
FORCEPROP 2 LASTPIN (425 2625) $PN 22
J 0
(435 2635);
DISPLAY 0.617021 (435 2635);
PAINT MONO (435 2635);
FORCEPROP 2 LASTPIN (-375 2625) $PN 21
J 2
(-385 2635);
DISPLAY 0.617021 (-385 2635);
PAINT MONO (-385 2635);
FORCEPROP 2 LASTPIN (425 2675) $PN 20
J 0
(435 2685);
DISPLAY 0.617021 (435 2685);
PAINT MONO (435 2685);
FORCEPROP 2 LASTPIN (-375 2675) $PN 19
J 2
(-385 2685);
DISPLAY 0.617021 (-385 2685);
PAINT MONO (-385 2685);
FORCEPROP 2 LASTPIN (425 2725) $PN 18
J 0
(435 2735);
DISPLAY 0.617021 (435 2735);
PAINT MONO (435 2735);
FORCEPROP 2 LASTPIN (-375 2725) $PN 17
J 2
(-385 2735);
DISPLAY 0.617021 (-385 2735);
PAINT MONO (-385 2735);
FORCEPROP 2 LASTPIN (425 2775) $PN 16
J 0
(435 2785);
DISPLAY 0.617021 (435 2785);
PAINT MONO (435 2785);
FORCEPROP 2 LASTPIN (-375 2775) $PN 15
J 2
(-385 2785);
DISPLAY 0.617021 (-385 2785);
PAINT MONO (-385 2785);
FORCEPROP 2 LASTPIN (425 2825) $PN 14
J 0
(435 2835);
DISPLAY 0.617021 (435 2835);
PAINT MONO (435 2835);
FORCEPROP 2 LASTPIN (-375 2825) $PN 13
J 2
(-385 2835);
DISPLAY 0.617021 (-385 2835);
PAINT MONO (-385 2835);
FORCEPROP 2 LASTPIN (425 2875) $PN 12
J 0
(435 2885);
DISPLAY 0.617021 (435 2885);
PAINT MONO (435 2885);
FORCEPROP 2 LASTPIN (-375 2875) $PN 11
J 2
(-385 2885);
DISPLAY 0.617021 (-385 2885);
PAINT MONO (-385 2885);
FORCEPROP 2 LASTPIN (425 2925) $PN 10
J 0
(435 2935);
DISPLAY 0.617021 (435 2935);
PAINT MONO (435 2935);
FORCEPROP 2 LASTPIN (-375 2925) $PN 9
J 2
(-385 2935);
DISPLAY 0.617021 (-385 2935);
PAINT MONO (-385 2935);
FORCEPROP 2 LASTPIN (425 2975) $PN 8
J 0
(435 2985);
DISPLAY 0.617021 (435 2985);
PAINT MONO (435 2985);
FORCEPROP 2 LASTPIN (-375 2975) $PN 7
J 2
(-385 2985);
DISPLAY 0.617021 (-385 2985);
PAINT MONO (-385 2985);
FORCEPROP 2 LASTPIN (425 3025) $PN 6
J 0
(435 3035);
DISPLAY 0.617021 (435 3035);
PAINT MONO (435 3035);
FORCEPROP 2 LASTPIN (-375 3025) $PN 5
J 2
(-385 3035);
DISPLAY 0.617021 (-385 3035);
PAINT MONO (-385 3035);
FORCEPROP 2 LASTPIN (425 3075) $PN 4
J 0
(435 3085);
DISPLAY 0.617021 (435 3085);
PAINT MONO (435 3085);
FORCEPROP 2 LASTPIN (-375 3075) $PN 3
J 2
(-385 3085);
DISPLAY 0.617021 (-385 3085);
PAINT MONO (-385 3085);
FORCEPROP 2 LASTPIN (425 3125) $PN 2
J 0
(435 3135);
DISPLAY 0.617021 (435 3135);
PAINT MONO (435 3135);
FORCEPROP 2 LASTPIN (-375 3125) $PN 1
J 2
(-385 3135);
DISPLAY 0.617021 (-385 3135);
PAINT MONO (-385 3135);
FORCEPROP 1 LAST PACK_TYPE SM
J 0
(-325 3425);
DISPLAY 1.340426 (-325 3425);
PAINT SKYBLUE (-325 3425);
DISPLAY INVISIBLE (-325 3425);
FORCEPROP 2 LAST CDS_LIB mstr_sconn
J 0
(25 2825);
PAINT ORANGE (25 2825);
DISPLAY INVISIBLE (25 2825);
FORCEPROP 2 LAST CDS_SEC 1
J 0
(-325 3425);
PAINT MONO (-325 3425);
DISPLAY INVISIBLE (-325 3425);
FORCEPROP 2 LAST $SEC 1
J 0
(-325 3425);
PAINT MONO (-325 3425);
DISPLAY INVISIBLE (-325 3425);
FORCEPROP 2 LAST CDS_LOCATION J8B1
J 0
(-325 3375);
DISPLAY 0.617021 (-325 3375);
PAINT AQUA (-325 3375);
DISPLAY INVISIBLE (-325 3375);
FORCEPROP 1 LAST PATH I1
J 0
(25 3325);
PAINT GREEN (25 3325);
DISPLAY INVISIBLE (25 3325);
FORCEPROP 0 LAST ROOM HFI
J 0
(-325 3475);
DISPLAY 1.021277 (-325 3475);
PAINT ORANGE (-325 3475);
DISPLAY INVISIBLE (-325 3475);
FORCEADD OFFPAGE..4
(2925 2925);
FORCEPROP 2 LAST $XR0 29 
J 0
(3111 2925);
DISPLAY 0.638298 (3111 2925);
PAINT MONO (3111 2925);
FORCEPROP 2 LAST CDS_LIB mstr_standard
J 0
(2925 2925);
DISPLAY 1.340426 (2925 2925);
PAINT MONO (2925 2925);
DISPLAY INVISIBLE (2925 2925);
FORCEPROP 1 LAST OFFPAGE TRUE
J 0
(3250 2800);
DISPLAY 1.170213 (3250 2800);
PAINT GREEN (3250 2800);
DISPLAY INVISIBLE (3250 2800);
FORCEPROP 1 LAST COMMENT_BODY TRUE
J 0
(2900 2825);
DISPLAY 1.170213 (2900 2825);
PAINT GREEN (2900 2825);
DISPLAY INVISIBLE (2900 2825);
FORCEPROP 2 LAST PATH I10
J 0
(3250 2975);
DISPLAY 1.021277 (3250 2975);
PAINT ORANGE (3250 2975);
DISPLAY INVISIBLE (3250 2975);
FORCEADD OFFPAGE..4
(2950 2625);
FORCEPROP 2 LAST $XR0 138 
J 0
(3136 2625);
DISPLAY 0.638298 (3136 2625);
PAINT MONO (3136 2625);
FORCEPROP 2 LAST $XR1 159 
J 0
(3256 2625);
DISPLAY 0.638298 (3256 2625);
PAINT MONO (3256 2625);
FORCEPROP 2 LAST $XR2 186 
J 0
(3376 2625);
DISPLAY 0.638298 (3376 2625);
PAINT MONO (3376 2625);
FORCEPROP 2 LAST $XR3 188 
J 0
(3496 2625);
DISPLAY 0.638298 (3496 2625);
PAINT MONO (3496 2625);
FORCEPROP 2 LAST CDS_LIB mstr_standard
J 0
(2950 2625);
DISPLAY 1.340426 (2950 2625);
PAINT MONO (2950 2625);
DISPLAY INVISIBLE (2950 2625);
FORCEPROP 1 LAST OFFPAGE TRUE
J 0
(3275 2500);
DISPLAY 1.170213 (3275 2500);
PAINT GREEN (3275 2500);
DISPLAY INVISIBLE (3275 2500);
FORCEPROP 1 LAST COMMENT_BODY TRUE
J 0
(2925 2525);
DISPLAY 1.170213 (2925 2525);
PAINT GREEN (2925 2525);
DISPLAY INVISIBLE (2925 2525);
FORCEPROP 2 LAST PATH I11
J 0
(3300 2725);
DISPLAY 1.021277 (3300 2725);
PAINT ORANGE (3300 2725);
DISPLAY INVISIBLE (3300 2725);
FORCEADD OFFPAGE..3
(2950 2575);
FORCEPROP 2 LAST $XR0 138 
J 0
(3164 2575);
DISPLAY 0.638298 (3164 2575);
PAINT MONO (3164 2575);
FORCEPROP 2 LAST $XR1 159 
J 0
(3284 2575);
DISPLAY 0.638298 (3284 2575);
PAINT MONO (3284 2575);
FORCEPROP 2 LAST $XR2 186 
J 0
(3404 2575);
DISPLAY 0.638298 (3404 2575);
PAINT MONO (3404 2575);
FORCEPROP 2 LAST $XR3 188 
J 0
(3524 2575);
DISPLAY 0.638298 (3524 2575);
PAINT MONO (3524 2575);
FORCEPROP 2 LAST CDS_LIB mstr_standard
J 0
(2950 2575);
DISPLAY 1.340426 (2950 2575);
PAINT MONO (2950 2575);
DISPLAY INVISIBLE (2950 2575);
FORCEPROP 1 LAST OFFPAGE TRUE
J 0
(3275 2450);
DISPLAY 1.170213 (3275 2450);
PAINT GREEN (3275 2450);
DISPLAY INVISIBLE (3275 2450);
FORCEPROP 1 LAST COMMENT_BODY TRUE
J 0
(2900 2475);
DISPLAY 1.170213 (2900 2475);
PAINT GREEN (2900 2475);
DISPLAY INVISIBLE (2900 2475);
FORCEPROP 2 LAST PATH I12
J 0
(3900 2625);
DISPLAY 1.021277 (3900 2625);
PAINT ORANGE (3900 2625);
DISPLAY INVISIBLE (3900 2625);
FORCEADD RES..2
(1400 3350);
FORCEPROP 1 LAST LOCATION R8B8
J 0
(1445 3475);
DISPLAY 0.617021 (1445 3475);
PAINT AQUA (1445 3475);
FORCEPROP 1 LAST PART_NUMBER G21796-072
J 0
(1440 3225);
DISPLAY 0.617021 (1440 3225);
PAINT BLUE (1440 3225);
FORCEPROP 1 LAST VALUE 4.75K
J 0
(1445 3425);
DISPLAY 0.617021 (1445 3425);
PAINT SKYBLUE (1445 3425);
FORCEPROP 1 LAST TOLERANCE 1%
J 0
(1445 3375);
DISPLAY 0.617021 (1445 3375);
PAINT SKYBLUE (1445 3375);
FORCEPROP 1 LAST PACK_TYPE 0402
J 0
(1440 3175);
DISPLAY 0.617021 (1440 3175);
PAINT SKYBLUE (1440 3175);
FORCEPROP 1 LAST MATERIAL CHIP
J 0
(1440 3275);
DISPLAY 0.617021 (1440 3275);
PAINT SKYBLUE (1440 3275);
FORCEPROP 1 LAST WATTAGE 1/16W
J 0
(1440 3325);
DISPLAY 0.617021 (1440 3325);
PAINT SKYBLUE (1440 3325);
FORCEPROP 1 LASTPIN (1400 3250) $PN 2
J 0
(1405 3260);
DISPLAY 0.617021 (1405 3260);
PAINT WHITE (1405 3260);
FORCEPROP 1 LASTPIN (1400 3450) $PN 1
J 0
(1405 3412);
DISPLAY 0.617021 (1405 3412);
PAINT WHITE (1405 3412);
FORCEPROP 2 LAST CDS_LIB mstr_discrete
J 0
(1400 3350);
DISPLAY 0.829787 (1400 3350);
PAINT ORANGE (1400 3350);
DISPLAY INVISIBLE (1400 3350);
FORCEPROP 2 LAST SEC_TYPE 0402
J 0
(1450 3575);
DISPLAY 1.361702 (1450 3575);
PAINT ORANGE (1450 3575);
DISPLAY INVISIBLE (1450 3575);
FORCEPROP 2 LAST SIGNAL_MODEL DEFAULT_RESISTOR_4750OHM_2_1
J 0
(1450 3575);
PAINT MONO (1450 3575);
DISPLAY INVISIBLE (1450 3575);
FORCEPROP 2 LAST SEC 1
J 0
(1450 3575);
DISPLAY 0.914894 (1450 3575);
PAINT MONO (1450 3575);
DISPLAY INVISIBLE (1450 3575);
FORCEPROP 2 LAST CDS_LOCATION R8B8
J 0
(1445 3475);
DISPLAY 0.617021 (1445 3475);
PAINT AQUA (1445 3475);
DISPLAY INVISIBLE (1445 3475);
FORCEPROP 1 LAST PATH I14
J 0
(1450 3525);
DISPLAY 0.978723 (1450 3525);
PAINT WHITE (1450 3525);
DISPLAY INVISIBLE (1450 3525);
FORCEPROP 0 LAST ROOM HFI
J 0
(1450 3525);
DISPLAY 1.021277 (1450 3525);
PAINT ORANGE (1450 3525);
DISPLAY INVISIBLE (1450 3525);
FORCEADD RES..2
(1150 3350);
FORCEPROP 1 LAST LOCATION R8B10
J 0
(1195 3475);
DISPLAY 0.617021 (1195 3475);
PAINT AQUA (1195 3475);
FORCEPROP 1 LAST PART_NUMBER G21796-072
J 0
(1190 3225);
DISPLAY 0.617021 (1190 3225);
PAINT BLUE (1190 3225);
FORCEPROP 1 LAST VALUE 4.75K
J 0
(1195 3425);
DISPLAY 0.617021 (1195 3425);
PAINT SKYBLUE (1195 3425);
FORCEPROP 1 LAST TOLERANCE 1%
J 0
(1195 3375);
DISPLAY 0.617021 (1195 3375);
PAINT SKYBLUE (1195 3375);
FORCEPROP 1 LAST PACK_TYPE 0402
J 0
(1190 3175);
DISPLAY 0.617021 (1190 3175);
PAINT SKYBLUE (1190 3175);
FORCEPROP 1 LAST MATERIAL CHIP
J 0
(1190 3275);
DISPLAY 0.617021 (1190 3275);
PAINT SKYBLUE (1190 3275);
FORCEPROP 1 LAST WATTAGE 1/16W
J 0
(1190 3325);
DISPLAY 0.617021 (1190 3325);
PAINT SKYBLUE (1190 3325);
FORCEPROP 1 LASTPIN (1150 3250) $PN 2
J 0
(1155 3260);
DISPLAY 0.617021 (1155 3260);
PAINT WHITE (1155 3260);
FORCEPROP 1 LASTPIN (1150 3450) $PN 1
J 0
(1155 3412);
DISPLAY 0.617021 (1155 3412);
PAINT WHITE (1155 3412);
FORCEPROP 2 LAST CDS_LIB mstr_discrete
J 0
(1150 3350);
DISPLAY 0.829787 (1150 3350);
PAINT ORANGE (1150 3350);
DISPLAY INVISIBLE (1150 3350);
FORCEPROP 2 LAST SEC_TYPE 0402
J 0
(1200 3575);
DISPLAY 1.361702 (1200 3575);
PAINT ORANGE (1200 3575);
DISPLAY INVISIBLE (1200 3575);
FORCEPROP 2 LAST SIGNAL_MODEL DEFAULT_RESISTOR_4750OHM_2_1
J 0
(1200 3575);
PAINT MONO (1200 3575);
DISPLAY INVISIBLE (1200 3575);
FORCEPROP 2 LAST SEC 1
J 0
(1200 3575);
DISPLAY 0.914894 (1200 3575);
PAINT MONO (1200 3575);
DISPLAY INVISIBLE (1200 3575);
FORCEPROP 2 LAST CDS_LOCATION R8B10
J 0
(1195 3475);
DISPLAY 0.617021 (1195 3475);
PAINT AQUA (1195 3475);
DISPLAY INVISIBLE (1195 3475);
FORCEPROP 1 LAST PATH I16
J 0
(1200 3525);
DISPLAY 0.978723 (1200 3525);
PAINT WHITE (1200 3525);
DISPLAY INVISIBLE (1200 3525);
FORCEPROP 0 LAST ROOM HFI
J 0
(1200 3525);
DISPLAY 1.021277 (1200 3525);
PAINT ORANGE (1200 3525);
DISPLAY INVISIBLE (1200 3525);
FORCEADD RES..2
(900 3350);
FORCEPROP 1 LAST LOCATION R8B16
J 0
(945 3475);
DISPLAY 0.617021 (945 3475);
PAINT AQUA (945 3475);
FORCEPROP 1 LAST PART_NUMBER G21796-072
J 0
(940 3225);
DISPLAY 0.617021 (940 3225);
PAINT BLUE (940 3225);
FORCEPROP 1 LAST VALUE 4.75K
J 0
(945 3425);
DISPLAY 0.617021 (945 3425);
PAINT SKYBLUE (945 3425);
FORCEPROP 1 LAST TOLERANCE 1%
J 0
(945 3375);
DISPLAY 0.617021 (945 3375);
PAINT SKYBLUE (945 3375);
FORCEPROP 1 LAST PACK_TYPE 0402
J 0
(940 3175);
DISPLAY 0.617021 (940 3175);
PAINT SKYBLUE (940 3175);
FORCEPROP 1 LAST MATERIAL CHIP
J 0
(940 3275);
DISPLAY 0.617021 (940 3275);
PAINT SKYBLUE (940 3275);
FORCEPROP 1 LAST WATTAGE 1/16W
J 0
(940 3325);
DISPLAY 0.617021 (940 3325);
PAINT SKYBLUE (940 3325);
FORCEPROP 1 LASTPIN (900 3250) $PN 2
J 0
(905 3260);
DISPLAY 0.617021 (905 3260);
PAINT WHITE (905 3260);
FORCEPROP 1 LASTPIN (900 3450) $PN 1
J 0
(905 3412);
DISPLAY 0.617021 (905 3412);
PAINT WHITE (905 3412);
FORCEPROP 2 LAST CDS_LIB mstr_discrete
J 0
(900 3350);
DISPLAY 0.829787 (900 3350);
PAINT ORANGE (900 3350);
DISPLAY INVISIBLE (900 3350);
FORCEPROP 2 LAST SEC_TYPE 0402
J 0
(950 3575);
DISPLAY 1.361702 (950 3575);
PAINT ORANGE (950 3575);
DISPLAY INVISIBLE (950 3575);
FORCEPROP 2 LAST SIGNAL_MODEL DEFAULT_RESISTOR_4750OHM_2_1
J 0
(950 3575);
PAINT MONO (950 3575);
DISPLAY INVISIBLE (950 3575);
FORCEPROP 2 LAST SEC 1
J 0
(950 3575);
DISPLAY 0.914894 (950 3575);
PAINT MONO (950 3575);
DISPLAY INVISIBLE (950 3575);
FORCEPROP 2 LAST CDS_LOCATION R8B16
J 0
(945 3475);
DISPLAY 0.617021 (945 3475);
PAINT AQUA (945 3475);
DISPLAY INVISIBLE (945 3475);
FORCEPROP 1 LAST PATH I17
J 0
(950 3525);
DISPLAY 0.978723 (950 3525);
PAINT WHITE (950 3525);
DISPLAY INVISIBLE (950 3525);
FORCEPROP 0 LAST ROOM HFI
J 0
(950 3525);
DISPLAY 1.021277 (950 3525);
PAINT ORANGE (950 3525);
DISPLAY INVISIBLE (950 3525);
FORCEADD RES..2
(650 3350);
FORCEPROP 1 LAST LOCATION R8B17
J 0
(695 3475);
DISPLAY 0.617021 (695 3475);
PAINT AQUA (695 3475);
FORCEPROP 1 LAST PART_NUMBER G21796-072
J 0
(690 3225);
DISPLAY 0.617021 (690 3225);
PAINT BLUE (690 3225);
FORCEPROP 1 LAST VALUE 4.75K
J 0
(695 3425);
DISPLAY 0.617021 (695 3425);
PAINT SKYBLUE (695 3425);
FORCEPROP 1 LAST TOLERANCE 1%
J 0
(695 3375);
DISPLAY 0.617021 (695 3375);
PAINT SKYBLUE (695 3375);
FORCEPROP 1 LAST PACK_TYPE 0402
J 0
(690 3175);
DISPLAY 0.617021 (690 3175);
PAINT SKYBLUE (690 3175);
FORCEPROP 1 LAST MATERIAL CHIP
J 0
(690 3275);
DISPLAY 0.617021 (690 3275);
PAINT SKYBLUE (690 3275);
FORCEPROP 1 LAST WATTAGE 1/16W
J 0
(690 3325);
DISPLAY 0.617021 (690 3325);
PAINT SKYBLUE (690 3325);
FORCEPROP 1 LASTPIN (650 3250) $PN 2
J 0
(655 3260);
DISPLAY 0.617021 (655 3260);
PAINT WHITE (655 3260);
FORCEPROP 1 LASTPIN (650 3450) $PN 1
J 0
(655 3412);
DISPLAY 0.617021 (655 3412);
PAINT WHITE (655 3412);
FORCEPROP 2 LAST SIGNAL_MODEL DEFAULT_RESISTOR_4750OHM_2_1
J 0
(700 3575);
PAINT MONO (700 3575);
DISPLAY INVISIBLE (700 3575);
FORCEPROP 2 LAST SEC_TYPE 0402
J 0
(700 3575);
DISPLAY 1.361702 (700 3575);
PAINT ORANGE (700 3575);
DISPLAY INVISIBLE (700 3575);
FORCEPROP 2 LAST CDS_LIB mstr_discrete
J 0
(650 3350);
DISPLAY 0.829787 (650 3350);
PAINT ORANGE (650 3350);
DISPLAY INVISIBLE (650 3350);
FORCEPROP 2 LAST SEC 1
J 0
(700 3575);
DISPLAY 0.914894 (700 3575);
PAINT MONO (700 3575);
DISPLAY INVISIBLE (700 3575);
FORCEPROP 2 LAST CDS_LOCATION R8B17
J 0
(695 3475);
DISPLAY 0.617021 (695 3475);
PAINT AQUA (695 3475);
DISPLAY INVISIBLE (695 3475);
FORCEPROP 1 LAST PATH I18
J 0
(700 3525);
DISPLAY 0.978723 (700 3525);
PAINT WHITE (700 3525);
DISPLAY INVISIBLE (700 3525);
FORCEPROP 0 LAST ROOM HFI
J 0
(700 3525);
DISPLAY 1.021277 (700 3525);
PAINT ORANGE (700 3525);
DISPLAY INVISIBLE (700 3525);
FORCEADD GND..1
(-475 2325);
FORCEPROP 3 LASTPIN (-475 2375) SIG_NAME GND\g
J 0
(-465 2385);
DISPLAY 0.659574 (-465 2385);
PAINT MONO (-465 2385);
DISPLAY INVISIBLE (-465 2385);
FORCEPROP 1 LAST VOLTAGE 0.0V
J 0
(-520 2282);
DISPLAY 0.340426 (-520 2282);
PAINT SKYBLUE (-520 2282);
DISPLAY INVISIBLE (-520 2282);
FORCEPROP 2 LAST CDS_LIB mstr_symbols
J 0
(-475 2325);
DISPLAY 1.340426 (-475 2325);
PAINT MONO (-475 2325);
DISPLAY INVISIBLE (-475 2325);
FORCEPROP 1 LAST SIZE 1B
J 0
(-400 2275);
DISPLAY 1.170213 (-400 2275);
PAINT AQUA (-400 2275);
DISPLAY INVISIBLE (-400 2275);
FORCEPROP 1 LAST BODY_TYPE PLUMBING
J 0
(-520 2282);
DISPLAY 0.340426 (-520 2282);
PAINT GREEN (-520 2282);
DISPLAY INVISIBLE (-520 2282);
FORCEPROP 1 LAST PATH I2
J 0
(-400 2325);
DISPLAY 0.872340 (-400 2325);
PAINT AQUA (-400 2325);
DISPLAY INVISIBLE (-400 2325);
FORCEPROP 1 LAST HDL_POWER GND
J 0
(-475 2475);
DISPLAY 1.170213 (-475 2475);
PAINT GREEN (-475 2475);
DISPLAY INVISIBLE (-475 2475);
FORCEADD RES..2
R 2
(-600 3325);
FORCEPROP 1 LAST LOCATION R8B18
J 2
(-645 3450);
DISPLAY 0.617021 (-645 3450);
PAINT AQUA (-645 3450);
FORCEPROP 1 LAST PART_NUMBER G21796-072
J 2
(-640 3200);
DISPLAY 0.617021 (-640 3200);
PAINT BLUE (-640 3200);
FORCEPROP 1 LAST VALUE 4.75K
J 2
(-645 3400);
DISPLAY 0.617021 (-645 3400);
PAINT SKYBLUE (-645 3400);
FORCEPROP 1 LAST TOLERANCE 1%
J 2
(-645 3350);
DISPLAY 0.617021 (-645 3350);
PAINT SKYBLUE (-645 3350);
FORCEPROP 1 LAST PACK_TYPE 0402
J 2
(-640 3150);
DISPLAY 0.617021 (-640 3150);
PAINT SKYBLUE (-640 3150);
FORCEPROP 1 LAST MATERIAL CHIP
J 2
(-640 3250);
DISPLAY 0.617021 (-640 3250);
PAINT SKYBLUE (-640 3250);
FORCEPROP 1 LAST WATTAGE 1/16W
J 2
(-640 3300);
DISPLAY 0.617021 (-640 3300);
PAINT SKYBLUE (-640 3300);
FORCEPROP 1 LASTPIN (-600 3225) $PN 2
J 2
(-605 3235);
DISPLAY 0.617021 (-605 3235);
PAINT WHITE (-605 3235);
FORCEPROP 1 LASTPIN (-600 3425) $PN 1
J 2
(-605 3387);
DISPLAY 0.617021 (-605 3387);
PAINT WHITE (-605 3387);
FORCEPROP 2 LAST SIGNAL_MODEL DEFAULT_RESISTOR_4750OHM_2_1
J 0
(-650 3550);
PAINT MONO (-650 3550);
DISPLAY INVISIBLE (-650 3550);
FORCEPROP 2 LAST CDS_LIB mstr_discrete
J 2
(-600 3325);
DISPLAY 0.829787 (-600 3325);
PAINT ORANGE (-600 3325);
DISPLAY INVISIBLE (-600 3325);
FORCEPROP 2 LAST SEC_TYPE 0402
J 2
(-650 3550);
DISPLAY 1.361702 (-650 3550);
PAINT ORANGE (-650 3550);
DISPLAY INVISIBLE (-650 3550);
FORCEPROP 2 LAST SEC 1
J 2
(-650 3550);
DISPLAY 0.914894 (-650 3550);
PAINT MONO (-650 3550);
DISPLAY INVISIBLE (-650 3550);
FORCEPROP 2 LAST CDS_LOCATION R8B18
J 2
(-645 3450);
DISPLAY 0.617021 (-645 3450);
PAINT AQUA (-645 3450);
DISPLAY INVISIBLE (-645 3450);
FORCEPROP 1 LAST PATH I20
J 2
(-650 3500);
DISPLAY 0.978723 (-650 3500);
PAINT WHITE (-650 3500);
DISPLAY INVISIBLE (-650 3500);
FORCEPROP 0 LAST ROOM HFI
J 0
(-625 3500);
DISPLAY 1.021277 (-625 3500);
PAINT ORANGE (-625 3500);
DISPLAY INVISIBLE (-625 3500);
FORCEADD RES..2
R 2
(-975 3325);
FORCEPROP 1 LAST LOCATION R8B19
J 2
(-1020 3450);
DISPLAY 0.617021 (-1020 3450);
PAINT AQUA (-1020 3450);
FORCEPROP 1 LAST PART_NUMBER G21796-072
J 2
(-1015 3200);
DISPLAY 0.617021 (-1015 3200);
PAINT BLUE (-1015 3200);
FORCEPROP 1 LAST VALUE 4.75K
J 2
(-1020 3400);
DISPLAY 0.617021 (-1020 3400);
PAINT SKYBLUE (-1020 3400);
FORCEPROP 1 LAST TOLERANCE 1%
J 2
(-1020 3350);
DISPLAY 0.617021 (-1020 3350);
PAINT SKYBLUE (-1020 3350);
FORCEPROP 1 LAST PACK_TYPE 0402
J 2
(-1015 3150);
DISPLAY 0.617021 (-1015 3150);
PAINT SKYBLUE (-1015 3150);
FORCEPROP 1 LAST MATERIAL CHIP
J 2
(-1015 3250);
DISPLAY 0.617021 (-1015 3250);
PAINT SKYBLUE (-1015 3250);
FORCEPROP 1 LAST WATTAGE 1/16W
J 2
(-1015 3300);
DISPLAY 0.617021 (-1015 3300);
PAINT SKYBLUE (-1015 3300);
FORCEPROP 1 LASTPIN (-975 3225) $PN 2
J 2
(-980 3235);
DISPLAY 0.617021 (-980 3235);
PAINT WHITE (-980 3235);
FORCEPROP 1 LASTPIN (-975 3425) $PN 1
J 2
(-980 3387);
DISPLAY 0.617021 (-980 3387);
PAINT WHITE (-980 3387);
FORCEPROP 2 LAST SIGNAL_MODEL DEFAULT_RESISTOR_4750OHM_2_1
J 0
(-1025 3550);
PAINT MONO (-1025 3550);
DISPLAY INVISIBLE (-1025 3550);
FORCEPROP 2 LAST CDS_LIB mstr_discrete
J 2
(-975 3325);
DISPLAY 0.829787 (-975 3325);
PAINT ORANGE (-975 3325);
DISPLAY INVISIBLE (-975 3325);
FORCEPROP 2 LAST SEC_TYPE 0402
J 2
(-1025 3550);
DISPLAY 1.361702 (-1025 3550);
PAINT ORANGE (-1025 3550);
DISPLAY INVISIBLE (-1025 3550);
FORCEPROP 2 LAST SEC 1
J 2
(-1025 3550);
DISPLAY 0.914894 (-1025 3550);
PAINT MONO (-1025 3550);
DISPLAY INVISIBLE (-1025 3550);
FORCEPROP 2 LAST CDS_LOCATION R8B19
J 2
(-1020 3450);
DISPLAY 0.617021 (-1020 3450);
PAINT AQUA (-1020 3450);
DISPLAY INVISIBLE (-1020 3450);
FORCEPROP 1 LAST PATH I21
J 2
(-1025 3500);
DISPLAY 0.978723 (-1025 3500);
PAINT WHITE (-1025 3500);
DISPLAY INVISIBLE (-1025 3500);
FORCEPROP 0 LAST ROOM HFI
J 0
(-1000 3500);
DISPLAY 1.021277 (-1000 3500);
PAINT ORANGE (-1000 3500);
DISPLAY INVISIBLE (-1000 3500);
FORCEADD RES..2
R 2
(-1350 3325);
FORCEPROP 1 LAST LOCATION R8B5
J 2
(-1395 3450);
DISPLAY 0.617021 (-1395 3450);
PAINT AQUA (-1395 3450);
FORCEPROP 1 LAST PART_NUMBER G21796-072
J 2
(-1390 3200);
DISPLAY 0.617021 (-1390 3200);
PAINT BLUE (-1390 3200);
FORCEPROP 1 LAST VALUE 4.75K
J 2
(-1395 3400);
DISPLAY 0.617021 (-1395 3400);
PAINT SKYBLUE (-1395 3400);
FORCEPROP 1 LAST TOLERANCE 1%
J 2
(-1395 3350);
DISPLAY 0.617021 (-1395 3350);
PAINT SKYBLUE (-1395 3350);
FORCEPROP 1 LAST PACK_TYPE 0402
J 2
(-1390 3150);
DISPLAY 0.617021 (-1390 3150);
PAINT SKYBLUE (-1390 3150);
FORCEPROP 1 LAST MATERIAL CHIP
J 2
(-1390 3250);
DISPLAY 0.617021 (-1390 3250);
PAINT SKYBLUE (-1390 3250);
FORCEPROP 1 LAST WATTAGE 1/16W
J 2
(-1390 3300);
DISPLAY 0.617021 (-1390 3300);
PAINT SKYBLUE (-1390 3300);
FORCEPROP 1 LASTPIN (-1350 3225) $PN 2
J 2
(-1355 3235);
DISPLAY 0.617021 (-1355 3235);
PAINT WHITE (-1355 3235);
FORCEPROP 1 LASTPIN (-1350 3425) $PN 1
J 2
(-1355 3387);
DISPLAY 0.617021 (-1355 3387);
PAINT WHITE (-1355 3387);
FORCEPROP 2 LAST SIGNAL_MODEL DEFAULT_RESISTOR_4750OHM_2_1
J 0
(-1400 3550);
PAINT MONO (-1400 3550);
DISPLAY INVISIBLE (-1400 3550);
FORCEPROP 2 LAST CDS_LIB mstr_discrete
J 2
(-1350 3325);
DISPLAY 0.829787 (-1350 3325);
PAINT ORANGE (-1350 3325);
DISPLAY INVISIBLE (-1350 3325);
FORCEPROP 2 LAST SEC_TYPE 0402
J 2
(-1400 3550);
DISPLAY 1.361702 (-1400 3550);
PAINT ORANGE (-1400 3550);
DISPLAY INVISIBLE (-1400 3550);
FORCEPROP 2 LAST SEC 1
J 2
(-1400 3550);
DISPLAY 0.914894 (-1400 3550);
PAINT MONO (-1400 3550);
DISPLAY INVISIBLE (-1400 3550);
FORCEPROP 2 LAST CDS_LOCATION R8B5
J 2
(-1395 3450);
DISPLAY 0.617021 (-1395 3450);
PAINT AQUA (-1395 3450);
DISPLAY INVISIBLE (-1395 3450);
FORCEPROP 1 LAST PATH I22
J 2
(-1400 3500);
DISPLAY 0.978723 (-1400 3500);
PAINT WHITE (-1400 3500);
DISPLAY INVISIBLE (-1400 3500);
FORCEPROP 0 LAST ROOM HFI
J 0
(-1375 3500);
DISPLAY 1.021277 (-1375 3500);
PAINT ORANGE (-1375 3500);
DISPLAY INVISIBLE (-1375 3500);
FORCEADD RES..2
R 2
(-1725 3325);
FORCEPROP 1 LAST LOCATION R8B3
J 2
(-1770 3450);
DISPLAY 0.617021 (-1770 3450);
PAINT AQUA (-1770 3450);
FORCEPROP 1 LAST PART_NUMBER G21796-072
J 2
(-1765 3200);
DISPLAY 0.617021 (-1765 3200);
PAINT BLUE (-1765 3200);
FORCEPROP 1 LAST VALUE 4.75K
J 2
(-1770 3400);
DISPLAY 0.617021 (-1770 3400);
PAINT SKYBLUE (-1770 3400);
FORCEPROP 1 LAST TOLERANCE 1%
J 2
(-1770 3350);
DISPLAY 0.617021 (-1770 3350);
PAINT SKYBLUE (-1770 3350);
FORCEPROP 1 LAST PACK_TYPE 0402
J 2
(-1765 3150);
DISPLAY 0.617021 (-1765 3150);
PAINT SKYBLUE (-1765 3150);
FORCEPROP 1 LAST MATERIAL CHIP
J 2
(-1765 3250);
DISPLAY 0.617021 (-1765 3250);
PAINT SKYBLUE (-1765 3250);
FORCEPROP 1 LAST WATTAGE 1/16W
J 2
(-1765 3300);
DISPLAY 0.617021 (-1765 3300);
PAINT SKYBLUE (-1765 3300);
FORCEPROP 1 LASTPIN (-1725 3225) $PN 2
J 2
(-1730 3235);
DISPLAY 0.617021 (-1730 3235);
PAINT WHITE (-1730 3235);
FORCEPROP 1 LASTPIN (-1725 3425) $PN 1
J 2
(-1730 3387);
DISPLAY 0.617021 (-1730 3387);
PAINT WHITE (-1730 3387);
FORCEPROP 2 LAST SIGNAL_MODEL DEFAULT_RESISTOR_4750OHM_2_1
J 0
(-1775 3550);
PAINT MONO (-1775 3550);
DISPLAY INVISIBLE (-1775 3550);
FORCEPROP 2 LAST CDS_LIB mstr_discrete
J 2
(-1725 3325);
DISPLAY 0.829787 (-1725 3325);
PAINT ORANGE (-1725 3325);
DISPLAY INVISIBLE (-1725 3325);
FORCEPROP 2 LAST SEC_TYPE 0402
J 2
(-1775 3550);
DISPLAY 1.361702 (-1775 3550);
PAINT ORANGE (-1775 3550);
DISPLAY INVISIBLE (-1775 3550);
FORCEPROP 2 LAST SEC 1
J 2
(-1775 3550);
DISPLAY 0.914894 (-1775 3550);
PAINT MONO (-1775 3550);
DISPLAY INVISIBLE (-1775 3550);
FORCEPROP 2 LAST CDS_LOCATION R8B3
J 2
(-1770 3450);
DISPLAY 0.617021 (-1770 3450);
PAINT AQUA (-1770 3450);
DISPLAY INVISIBLE (-1770 3450);
FORCEPROP 1 LAST PATH I24
J 2
(-1775 3500);
DISPLAY 0.978723 (-1775 3500);
PAINT WHITE (-1775 3500);
DISPLAY INVISIBLE (-1775 3500);
FORCEPROP 0 LAST ROOM HFI
J 0
(-1750 3550);
DISPLAY 1.021277 (-1750 3550);
PAINT ORANGE (-1750 3550);
DISPLAY INVISIBLE (-1750 3550);
FORCEADD OFFPAGE..5
(-2800 3075);
FORCEPROP 2 LAST $XR0 29 
J 0
(-3024 3075);
DISPLAY 0.638298 (-3024 3075);
PAINT MONO (-3024 3075);
FORCEPROP 2 LAST CDS_LIB mstr_standard
J 0
(-2800 3075);
DISPLAY 1.340426 (-2800 3075);
PAINT MONO (-2800 3075);
DISPLAY INVISIBLE (-2800 3075);
FORCEPROP 1 LAST OFFPAGE TRUE
J 0
(-2475 2950);
DISPLAY 0.829787 (-2475 2950);
PAINT GREEN (-2475 2950);
DISPLAY INVISIBLE (-2475 2950);
FORCEPROP 1 LAST COMMENT_BODY TRUE
J 0
(-2700 3000);
DISPLAY 1.170213 (-2700 3000);
PAINT PEACH (-2700 3000);
DISPLAY INVISIBLE (-2700 3000);
FORCEPROP 2 LAST PATH I25
J 0
(-3050 3125);
DISPLAY 1.021277 (-3050 3125);
PAINT ORANGE (-3050 3125);
DISPLAY INVISIBLE (-3050 3125);
FORCEADD OFFPAGE..1
(-2800 3025);
FORCEPROP 2 LAST $XR0 29 
J 0
(-3051 3025);
DISPLAY 0.638298 (-3051 3025);
PAINT MONO (-3051 3025);
FORCEPROP 2 LAST CDS_LIB mstr_standard
J 0
(-2800 3025);
DISPLAY 1.340426 (-2800 3025);
PAINT MONO (-2800 3025);
DISPLAY INVISIBLE (-2800 3025);
FORCEPROP 1 LAST OFFPAGE TRUE
J 0
(-2475 2900);
DISPLAY 0.829787 (-2475 2900);
PAINT GREEN (-2475 2900);
DISPLAY INVISIBLE (-2475 2900);
FORCEPROP 1 LAST COMMENT_BODY TRUE
J 0
(-2675 2925);
DISPLAY 1.170213 (-2675 2925);
PAINT PEACH (-2675 2925);
DISPLAY INVISIBLE (-2675 2925);
FORCEPROP 2 LAST PATH I26
J 0
(-3075 3075);
DISPLAY 1.021277 (-3075 3075);
PAINT ORANGE (-3075 3075);
DISPLAY INVISIBLE (-3075 3075);
FORCEADD OFFPAGE..1
(-2800 2825);
FORCEPROP 2 LAST $XR0 29 
J 0
(-3051 2825);
DISPLAY 0.638298 (-3051 2825);
PAINT MONO (-3051 2825);
FORCEPROP 2 LAST CDS_LIB mstr_standard
J 0
(-2800 2825);
DISPLAY 1.340426 (-2800 2825);
PAINT MONO (-2800 2825);
DISPLAY INVISIBLE (-2800 2825);
FORCEPROP 1 LAST OFFPAGE TRUE
J 0
(-2475 2700);
DISPLAY 0.829787 (-2475 2700);
PAINT GREEN (-2475 2700);
DISPLAY INVISIBLE (-2475 2700);
FORCEPROP 1 LAST COMMENT_BODY TRUE
J 0
(-2675 2725);
DISPLAY 1.170213 (-2675 2725);
PAINT PEACH (-2675 2725);
DISPLAY INVISIBLE (-2675 2725);
FORCEPROP 2 LAST PATH I27
J 0
(-3075 2875);
DISPLAY 1.021277 (-3075 2875);
PAINT ORANGE (-3075 2875);
DISPLAY INVISIBLE (-3075 2875);
FORCEADD OFFPAGE..5
(-2800 2875);
FORCEPROP 2 LAST $XR0 29 
J 0
(-3024 2875);
DISPLAY 0.638298 (-3024 2875);
PAINT MONO (-3024 2875);
FORCEPROP 2 LAST CDS_LIB mstr_standard
J 0
(-2800 2875);
DISPLAY 1.340426 (-2800 2875);
PAINT MONO (-2800 2875);
DISPLAY INVISIBLE (-2800 2875);
FORCEPROP 1 LAST OFFPAGE TRUE
J 0
(-2475 2750);
DISPLAY 0.829787 (-2475 2750);
PAINT GREEN (-2475 2750);
DISPLAY INVISIBLE (-2475 2750);
FORCEPROP 1 LAST COMMENT_BODY TRUE
J 0
(-2700 2800);
DISPLAY 1.170213 (-2700 2800);
PAINT PEACH (-2700 2800);
DISPLAY INVISIBLE (-2700 2800);
FORCEPROP 2 LAST PATH I28
J 0
(-3050 2925);
DISPLAY 1.021277 (-3050 2925);
PAINT ORANGE (-3050 2925);
DISPLAY INVISIBLE (-3050 2925);
FORCEADD OFFPAGE..1
(-2800 2675);
FORCEPROP 2 LAST $XR0 231 
J 0
(-3082 2675);
DISPLAY 0.638298 (-3082 2675);
PAINT MONO (-3082 2675);
FORCEPROP 2 LAST $XR1 190 
J 0
(-3202 2675);
DISPLAY 0.638298 (-3202 2675);
PAINT MONO (-3202 2675);
FORCEPROP 2 LAST CDS_LIB mstr_standard
J 0
(-2800 2675);
DISPLAY 0.829787 (-2800 2675);
PAINT ORANGE (-2800 2675);
DISPLAY INVISIBLE (-2800 2675);
FORCEPROP 1 LAST OFFPAGE TRUE
J 0
(-2475 2550);
DISPLAY 0.829787 (-2475 2550);
PAINT GREEN (-2475 2550);
DISPLAY INVISIBLE (-2475 2550);
FORCEPROP 1 LAST COMMENT_BODY TRUE
J 0
(-2675 2575);
DISPLAY 1.170213 (-2675 2575);
PAINT PEACH (-2675 2575);
DISPLAY INVISIBLE (-2675 2575);
FORCEPROP 2 LAST PATH I29
J 0
(-3100 2725);
DISPLAY 1.021277 (-3100 2725);
PAINT ORANGE (-3100 2725);
DISPLAY INVISIBLE (-3100 2725);
FORCEADD OFFPAGE..4
(2925 3025);
FORCEPROP 2 LAST $XR0 29 
J 0
(3141 3025);
DISPLAY 0.638298 (3141 3025);
PAINT MONO (3141 3025);
FORCEPROP 2 LAST CDS_LIB mstr_standard
J 0
(2925 3025);
DISPLAY 1.340426 (2925 3025);
PAINT MONO (2925 3025);
DISPLAY INVISIBLE (2925 3025);
FORCEPROP 1 LAST OFFPAGE TRUE
J 0
(3250 2900);
DISPLAY 0.829787 (3250 2900);
PAINT GREEN (3250 2900);
DISPLAY INVISIBLE (3250 2900);
FORCEPROP 1 LAST COMMENT_BODY TRUE
J 0
(2900 2925);
DISPLAY 1.170213 (2900 2925);
PAINT PEACH (2900 2925);
DISPLAY INVISIBLE (2900 2925);
FORCEPROP 2 LAST PATH I3
J 0
(3150 3075);
DISPLAY 1.021277 (3150 3075);
PAINT ORANGE (3150 3075);
DISPLAY INVISIBLE (3150 3075);
FORCEADD PVPP_ABC..1
(-1725 3625);
FORCEPROP 3 LASTPIN (-1725 3575) SIG_NAME PVPP_ABC\g
J 0
(-1715 3585);
DISPLAY 0.659574 (-1715 3585);
PAINT MONO (-1715 3585);
DISPLAY INVISIBLE (-1715 3585);
FORCEPROP 1 LAST VOLTAGE 2.5V
J 0
(-1770 3582);
DISPLAY 0.340426 (-1770 3582);
PAINT SKYBLUE (-1770 3582);
DISPLAY INVISIBLE (-1770 3582);
FORCEPROP 2 LAST BOM_COST PVPP_KLM_VR
J 0
(-1650 3725);
PAINT MONO (-1650 3725);
DISPLAY INVISIBLE (-1650 3725);
FORCEPROP 2 LAST CDS_LIB mstr_symbols
J 0
(-1725 3625);
PAINT ORANGE (-1725 3625);
DISPLAY INVISIBLE (-1725 3625);
FORCEPROP 1 LAST BODY_TYPE PLUMBING
J 0
(-1770 3582);
DISPLAY 0.340426 (-1770 3582);
PAINT GREEN (-1770 3582);
DISPLAY INVISIBLE (-1770 3582);
FORCEPROP 1 LAST PATH I30
J 0
(-1675 3650);
DISPLAY 0.872340 (-1675 3650);
PAINT AQUA (-1675 3650);
DISPLAY INVISIBLE (-1675 3650);
FORCEPROP 2 LAST ROOM PVPP_KLM_VR
J 0
(-1475 3725);
PAINT ORANGE (-1475 3725);
DISPLAY INVISIBLE (-1475 3725);
FORCEPROP 1 LAST HDL_POWER PVPP_ABC
J 1
(-1725 3675);
DISPLAY 0.872340 (-1725 3675);
PAINT GREEN (-1725 3675);
DISPLAY INVISIBLE (-1725 3675);
FORCEADD PVPP_ABC..1
(-525 3625);
FORCEPROP 3 LASTPIN (-525 3575) SIG_NAME PVPP_ABC\g
J 0
(-515 3585);
DISPLAY 0.659574 (-515 3585);
PAINT MONO (-515 3585);
DISPLAY INVISIBLE (-515 3585);
FORCEPROP 1 LAST VOLTAGE 2.5V
J 0
(-570 3582);
DISPLAY 0.340426 (-570 3582);
PAINT SKYBLUE (-570 3582);
DISPLAY INVISIBLE (-570 3582);
FORCEPROP 2 LAST BOM_COST PVPP_KLM_VR
J 0
(-450 3725);
PAINT MONO (-450 3725);
DISPLAY INVISIBLE (-450 3725);
FORCEPROP 2 LAST CDS_LIB mstr_symbols
J 0
(-525 3625);
PAINT ORANGE (-525 3625);
DISPLAY INVISIBLE (-525 3625);
FORCEPROP 1 LAST BODY_TYPE PLUMBING
J 0
(-570 3582);
DISPLAY 0.340426 (-570 3582);
PAINT GREEN (-570 3582);
DISPLAY INVISIBLE (-570 3582);
FORCEPROP 1 LAST PATH I31
J 0
(-475 3650);
DISPLAY 0.872340 (-475 3650);
PAINT AQUA (-475 3650);
DISPLAY INVISIBLE (-475 3650);
FORCEPROP 2 LAST ROOM PVPP_KLM_VR
J 0
(-275 3725);
PAINT ORANGE (-275 3725);
DISPLAY INVISIBLE (-275 3725);
FORCEPROP 1 LAST HDL_POWER PVPP_ABC
J 1
(-525 3675);
DISPLAY 0.872340 (-525 3675);
PAINT GREEN (-525 3675);
DISPLAY INVISIBLE (-525 3675);
FORCEADD PVPP_ABC..1
(2400 3675);
FORCEPROP 3 LASTPIN (2400 3625) SIG_NAME PVPP_ABC\g
J 0
(2410 3635);
DISPLAY 0.659574 (2410 3635);
PAINT MONO (2410 3635);
DISPLAY INVISIBLE (2410 3635);
FORCEPROP 1 LAST VOLTAGE 2.5V
J 0
(2355 3632);
DISPLAY 0.340426 (2355 3632);
PAINT SKYBLUE (2355 3632);
DISPLAY INVISIBLE (2355 3632);
FORCEPROP 2 LAST BOM_COST PVPP_KLM_VR
J 0
(2475 3775);
PAINT MONO (2475 3775);
DISPLAY INVISIBLE (2475 3775);
FORCEPROP 2 LAST CDS_LIB mstr_symbols
J 0
(2400 3675);
PAINT ORANGE (2400 3675);
DISPLAY INVISIBLE (2400 3675);
FORCEPROP 1 LAST BODY_TYPE PLUMBING
J 0
(2355 3632);
DISPLAY 0.340426 (2355 3632);
PAINT GREEN (2355 3632);
DISPLAY INVISIBLE (2355 3632);
FORCEPROP 1 LAST PATH I32
J 0
(2450 3700);
DISPLAY 0.872340 (2450 3700);
PAINT AQUA (2450 3700);
DISPLAY INVISIBLE (2450 3700);
FORCEPROP 2 LAST ROOM PVPP_KLM_VR
J 0
(2650 3775);
PAINT ORANGE (2650 3775);
DISPLAY INVISIBLE (2650 3775);
FORCEPROP 1 LAST HDL_POWER PVPP_ABC
J 1
(2400 3725);
DISPLAY 0.872340 (2400 3725);
PAINT GREEN (2400 3725);
DISPLAY INVISIBLE (2400 3725);
FORCEADD P3V3..1
(575 3625);
FORCEPROP 3 LASTPIN (575 3575) SIG_NAME P3V3\g
J 0
(585 3585);
DISPLAY 0.659574 (585 3585);
PAINT MONO (585 3585);
DISPLAY INVISIBLE (585 3585);
FORCEPROP 1 LAST VOLTAGE 3.3V
J 0
(530 3582);
DISPLAY 0.340426 (530 3582);
PAINT SKYBLUE (530 3582);
DISPLAY INVISIBLE (530 3582);
FORCEPROP 2 LAST CDS_LIB mstr_symbols
J 0
(575 3625);
PAINT MONO (575 3625);
DISPLAY INVISIBLE (575 3625);
FORCEPROP 1 LAST SIZE 1B
J 0
(620 3647);
DISPLAY 0.340426 (620 3647);
PAINT GREEN (620 3647);
DISPLAY INVISIBLE (620 3647);
FORCEPROP 1 LAST BODY_TYPE PLUMBING
J 0
(530 3582);
DISPLAY 0.340426 (530 3582);
PAINT GREEN (530 3582);
DISPLAY INVISIBLE (530 3582);
FORCEPROP 1 LAST PATH I33
J 0
(620 3627);
DISPLAY 0.340426 (620 3627);
PAINT GREEN (620 3627);
DISPLAY INVISIBLE (620 3627);
FORCEPROP 1 LAST HDL_POWER P3V3
J 0
(250 3500);
DISPLAY 0.872340 (250 3500);
PAINT ORANGE (250 3500);
DISPLAY INVISIBLE (250 3500);
FORCEADD RES..2
(1650 3350);
FORCEPROP 1 LAST LOCATION R8B13
J 0
(1695 3475);
DISPLAY 0.617021 (1695 3475);
PAINT AQUA (1695 3475);
FORCEPROP 1 LAST PART_NUMBER G21796-336
J 0
(1690 3225);
DISPLAY 0.617021 (1690 3225);
PAINT BLUE (1690 3225);
FORCEPROP 1 LAST VALUE 1.8K
J 0
(1695 3425);
DISPLAY 0.617021 (1695 3425);
PAINT SKYBLUE (1695 3425);
FORCEPROP 1 LAST TOLERANCE 1%
J 0
(1695 3375);
DISPLAY 0.617021 (1695 3375);
PAINT SKYBLUE (1695 3375);
FORCEPROP 1 LAST PACK_TYPE 0402
J 0
(1690 3175);
DISPLAY 0.617021 (1690 3175);
PAINT SKYBLUE (1690 3175);
FORCEPROP 1 LAST MATERIAL CHIP
J 0
(1690 3275);
DISPLAY 0.617021 (1690 3275);
PAINT SKYBLUE (1690 3275);
FORCEPROP 1 LAST WATTAGE 1/16W
J 0
(1690 3325);
DISPLAY 0.617021 (1690 3325);
PAINT SKYBLUE (1690 3325);
FORCEPROP 1 LASTPIN (1650 3250) $PN 2
J 0
(1655 3260);
DISPLAY 0.617021 (1655 3260);
PAINT ORANGE (1655 3260);
FORCEPROP 1 LASTPIN (1650 3450) $PN 1
J 0
(1655 3412);
DISPLAY 0.617021 (1655 3412);
PAINT ORANGE (1655 3412);
FORCEPROP 2 LAST CDS_LIB mstr_discrete
J 0
(1650 3350);
PAINT ORANGE (1650 3350);
DISPLAY INVISIBLE (1650 3350);
FORCEPROP 2 LAST SEC_TYPE 0402
J 0
(1700 3575);
DISPLAY 1.021277 (1700 3575);
PAINT ORANGE (1700 3575);
DISPLAY INVISIBLE (1700 3575);
FORCEPROP 2 LAST SEC 1
J 0
(1700 3575);
DISPLAY 0.680851 (1700 3575);
PAINT MONO (1700 3575);
DISPLAY INVISIBLE (1700 3575);
FORCEPROP 2 LAST CDS_LOCATION R8B13
J 0
(1695 3475);
DISPLAY 0.617021 (1695 3475);
PAINT AQUA (1695 3475);
DISPLAY INVISIBLE (1695 3475);
FORCEPROP 1 LAST PATH I34
J 0
(1700 3525);
DISPLAY 0.978723 (1700 3525);
PAINT WHITE (1700 3525);
DISPLAY INVISIBLE (1700 3525);
FORCEPROP 0 LAST ROOM SMBUS_CPU0_STL
J 0
(1700 3575);
DISPLAY 1.021277 (1700 3575);
PAINT ORANGE (1700 3575);
DISPLAY INVISIBLE (1700 3575);
FORCEADD RES..2
(1875 3350);
FORCEPROP 1 LAST LOCATION R8B11
J 0
(1920 3475);
DISPLAY 0.617021 (1920 3475);
PAINT AQUA (1920 3475);
FORCEPROP 1 LAST PART_NUMBER G21796-336
J 0
(1915 3225);
DISPLAY 0.617021 (1915 3225);
PAINT BLUE (1915 3225);
FORCEPROP 1 LAST VALUE 1.8K
J 0
(1920 3425);
DISPLAY 0.617021 (1920 3425);
PAINT SKYBLUE (1920 3425);
FORCEPROP 1 LAST TOLERANCE 1%
J 0
(1920 3375);
DISPLAY 0.617021 (1920 3375);
PAINT SKYBLUE (1920 3375);
FORCEPROP 1 LAST PACK_TYPE 0402
J 0
(1915 3175);
DISPLAY 0.617021 (1915 3175);
PAINT SKYBLUE (1915 3175);
FORCEPROP 1 LAST MATERIAL CHIP
J 0
(1915 3275);
DISPLAY 0.617021 (1915 3275);
PAINT SKYBLUE (1915 3275);
FORCEPROP 1 LAST WATTAGE 1/16W
J 0
(1915 3325);
DISPLAY 0.617021 (1915 3325);
PAINT SKYBLUE (1915 3325);
FORCEPROP 1 LASTPIN (1875 3250) $PN 2
J 0
(1880 3260);
DISPLAY 0.617021 (1880 3260);
PAINT ORANGE (1880 3260);
FORCEPROP 1 LASTPIN (1875 3450) $PN 1
J 0
(1880 3412);
DISPLAY 0.617021 (1880 3412);
PAINT ORANGE (1880 3412);
FORCEPROP 2 LAST CDS_LIB mstr_discrete
J 0
(1875 3350);
PAINT ORANGE (1875 3350);
DISPLAY INVISIBLE (1875 3350);
FORCEPROP 2 LAST SEC_TYPE 0402
J 0
(1925 3575);
DISPLAY 1.021277 (1925 3575);
PAINT ORANGE (1925 3575);
DISPLAY INVISIBLE (1925 3575);
FORCEPROP 2 LAST SEC 1
J 0
(1925 3575);
DISPLAY 0.680851 (1925 3575);
PAINT MONO (1925 3575);
DISPLAY INVISIBLE (1925 3575);
FORCEPROP 2 LAST CDS_LOCATION R8B11
J 0
(1920 3475);
DISPLAY 0.617021 (1920 3475);
PAINT AQUA (1920 3475);
DISPLAY INVISIBLE (1920 3475);
FORCEPROP 1 LAST PATH I35
J 0
(1925 3525);
DISPLAY 0.978723 (1925 3525);
PAINT WHITE (1925 3525);
DISPLAY INVISIBLE (1925 3525);
FORCEPROP 0 LAST ROOM SMBUS_CPU0_STL
J 0
(1925 3575);
DISPLAY 1.021277 (1925 3575);
PAINT ORANGE (1925 3575);
DISPLAY INVISIBLE (1925 3575);
FORCEADD RES..2
(2125 3350);
FORCEPROP 1 LAST LOCATION R8B7
J 0
(2170 3475);
DISPLAY 0.617021 (2170 3475);
PAINT AQUA (2170 3475);
FORCEPROP 1 LAST PART_NUMBER G21796-336
J 0
(2165 3225);
DISPLAY 0.617021 (2165 3225);
PAINT BLUE (2165 3225);
FORCEPROP 1 LAST VALUE 1.8K
J 0
(2170 3425);
DISPLAY 0.617021 (2170 3425);
PAINT SKYBLUE (2170 3425);
FORCEPROP 1 LAST TOLERANCE 1%
J 0
(2170 3375);
DISPLAY 0.617021 (2170 3375);
PAINT SKYBLUE (2170 3375);
FORCEPROP 1 LAST PACK_TYPE 0402
J 0
(2165 3175);
DISPLAY 0.617021 (2165 3175);
PAINT SKYBLUE (2165 3175);
FORCEPROP 1 LAST MATERIAL CHIP
J 0
(2165 3275);
DISPLAY 0.617021 (2165 3275);
PAINT SKYBLUE (2165 3275);
FORCEPROP 1 LAST WATTAGE 1/16W
J 0
(2165 3325);
DISPLAY 0.617021 (2165 3325);
PAINT SKYBLUE (2165 3325);
FORCEPROP 1 LASTPIN (2125 3250) $PN 2
J 0
(2130 3260);
DISPLAY 0.617021 (2130 3260);
PAINT ORANGE (2130 3260);
FORCEPROP 1 LASTPIN (2125 3450) $PN 1
J 0
(2130 3412);
DISPLAY 0.617021 (2130 3412);
PAINT ORANGE (2130 3412);
FORCEPROP 2 LAST CDS_LIB mstr_discrete
J 0
(2125 3350);
PAINT ORANGE (2125 3350);
DISPLAY INVISIBLE (2125 3350);
FORCEPROP 2 LAST SEC_TYPE 0402
J 0
(2175 3575);
DISPLAY 1.021277 (2175 3575);
PAINT ORANGE (2175 3575);
DISPLAY INVISIBLE (2175 3575);
FORCEPROP 2 LAST SEC 1
J 0
(2175 3575);
DISPLAY 0.680851 (2175 3575);
PAINT MONO (2175 3575);
DISPLAY INVISIBLE (2175 3575);
FORCEPROP 2 LAST CDS_LOCATION R8B7
J 0
(2170 3475);
DISPLAY 0.617021 (2170 3475);
PAINT AQUA (2170 3475);
DISPLAY INVISIBLE (2170 3475);
FORCEPROP 1 LAST PATH I36
J 0
(2175 3525);
DISPLAY 0.978723 (2175 3525);
PAINT WHITE (2175 3525);
DISPLAY INVISIBLE (2175 3525);
FORCEPROP 0 LAST ROOM SMBUS_CPU0_STL
J 0
(2175 3575);
DISPLAY 1.021277 (2175 3575);
PAINT ORANGE (2175 3575);
DISPLAY INVISIBLE (2175 3575);
FORCEADD RES..2
(2400 3350);
FORCEPROP 1 LAST LOCATION R8B6
J 0
(2445 3475);
DISPLAY 0.617021 (2445 3475);
PAINT AQUA (2445 3475);
FORCEPROP 1 LAST PART_NUMBER G21796-336
J 0
(2440 3225);
DISPLAY 0.617021 (2440 3225);
PAINT BLUE (2440 3225);
FORCEPROP 1 LAST VALUE 1.8K
J 0
(2445 3425);
DISPLAY 0.617021 (2445 3425);
PAINT SKYBLUE (2445 3425);
FORCEPROP 1 LAST TOLERANCE 1%
J 0
(2445 3375);
DISPLAY 0.617021 (2445 3375);
PAINT SKYBLUE (2445 3375);
FORCEPROP 1 LAST PACK_TYPE 0402
J 0
(2440 3175);
DISPLAY 0.617021 (2440 3175);
PAINT SKYBLUE (2440 3175);
FORCEPROP 1 LAST MATERIAL CHIP
J 0
(2440 3275);
DISPLAY 0.617021 (2440 3275);
PAINT SKYBLUE (2440 3275);
FORCEPROP 1 LAST WATTAGE 1/16W
J 0
(2440 3325);
DISPLAY 0.617021 (2440 3325);
PAINT SKYBLUE (2440 3325);
FORCEPROP 1 LASTPIN (2400 3250) $PN 2
J 0
(2405 3260);
DISPLAY 0.617021 (2405 3260);
PAINT ORANGE (2405 3260);
FORCEPROP 1 LASTPIN (2400 3450) $PN 1
J 0
(2405 3412);
DISPLAY 0.617021 (2405 3412);
PAINT ORANGE (2405 3412);
FORCEPROP 2 LAST CDS_LIB mstr_discrete
J 0
(2400 3350);
PAINT ORANGE (2400 3350);
DISPLAY INVISIBLE (2400 3350);
FORCEPROP 2 LAST SEC_TYPE 0402
J 0
(2450 3575);
DISPLAY 1.021277 (2450 3575);
PAINT ORANGE (2450 3575);
DISPLAY INVISIBLE (2450 3575);
FORCEPROP 2 LAST SEC 1
J 0
(2450 3575);
DISPLAY 0.680851 (2450 3575);
PAINT MONO (2450 3575);
DISPLAY INVISIBLE (2450 3575);
FORCEPROP 2 LAST CDS_LOCATION R8B6
J 0
(2445 3475);
DISPLAY 0.617021 (2445 3475);
PAINT AQUA (2445 3475);
DISPLAY INVISIBLE (2445 3475);
FORCEPROP 1 LAST PATH I37
J 0
(2450 3525);
DISPLAY 0.978723 (2450 3525);
PAINT WHITE (2450 3525);
DISPLAY INVISIBLE (2450 3525);
FORCEPROP 0 LAST ROOM SMBUS_CPU0_STL
J 0
(2450 3575);
DISPLAY 1.021277 (2450 3575);
PAINT ORANGE (2450 3575);
DISPLAY INVISIBLE (2450 3575);
FORCEADD GND..1
(525 2325);
FORCEPROP 3 LASTPIN (525 2375) SIG_NAME GND\g
J 0
(535 2385);
DISPLAY 0.659574 (535 2385);
PAINT MONO (535 2385);
DISPLAY INVISIBLE (535 2385);
FORCEPROP 1 LAST VOLTAGE 0.0V
J 0
(480 2282);
DISPLAY 0.340426 (480 2282);
PAINT SKYBLUE (480 2282);
DISPLAY INVISIBLE (480 2282);
FORCEPROP 1 LAST SIZE 1B
J 0
(600 2275);
DISPLAY 1.170213 (600 2275);
PAINT AQUA (600 2275);
DISPLAY INVISIBLE (600 2275);
FORCEPROP 2 LAST CDS_LIB mstr_symbols
J 0
(525 2325);
PAINT MONO (525 2325);
DISPLAY INVISIBLE (525 2325);
FORCEPROP 1 LAST BODY_TYPE PLUMBING
J 0
(480 2282);
DISPLAY 0.340426 (480 2282);
PAINT GREEN (480 2282);
DISPLAY INVISIBLE (480 2282);
FORCEPROP 1 LAST PATH I38
J 0
(600 2325);
DISPLAY 0.872340 (600 2325);
PAINT AQUA (600 2325);
DISPLAY INVISIBLE (600 2325);
FORCEPROP 1 LAST HDL_POWER GND
J 0
(525 2475);
DISPLAY 1.170213 (525 2475);
PAINT GREEN (525 2475);
DISPLAY INVISIBLE (525 2475);
FORCEADD OFFPAGE..4
(2925 3125);
FORCEPROP 2 LAST $XR0 29 
J 0
(3111 3125);
DISPLAY 0.638298 (3111 3125);
PAINT MONO (3111 3125);
FORCEPROP 2 LAST CDS_LIB mstr_standard
J 0
(2925 3125);
DISPLAY 1.340426 (2925 3125);
PAINT MONO (2925 3125);
DISPLAY INVISIBLE (2925 3125);
FORCEPROP 1 LAST OFFPAGE TRUE
J 0
(3250 3000);
DISPLAY 1.170213 (3250 3000);
PAINT GREEN (3250 3000);
DISPLAY INVISIBLE (3250 3000);
FORCEPROP 1 LAST COMMENT_BODY TRUE
J 0
(2900 3025);
DISPLAY 1.170213 (2900 3025);
PAINT GREEN (2900 3025);
DISPLAY INVISIBLE (2900 3025);
FORCEPROP 2 LAST PATH I4
J 0
(3250 3175);
DISPLAY 1.021277 (3250 3175);
PAINT ORANGE (3250 3175);
DISPLAY INVISIBLE (3250 3175);
FORCEADD OFFPAGE..3
(2925 3075);
FORCEPROP 2 LAST $XR0 29 
J 0
(3139 3075);
DISPLAY 0.638298 (3139 3075);
PAINT MONO (3139 3075);
FORCEPROP 2 LAST CDS_LIB mstr_standard
J 0
(2925 3075);
DISPLAY 1.340426 (2925 3075);
PAINT MONO (2925 3075);
DISPLAY INVISIBLE (2925 3075);
FORCEPROP 1 LAST OFFPAGE TRUE
J 0
(3250 2950);
DISPLAY 1.170213 (3250 2950);
PAINT GREEN (3250 2950);
DISPLAY INVISIBLE (3250 2950);
FORCEPROP 1 LAST COMMENT_BODY TRUE
J 0
(2875 2975);
DISPLAY 1.170213 (2875 2975);
PAINT GREEN (2875 2975);
DISPLAY INVISIBLE (2875 2975);
FORCEPROP 2 LAST PATH I5
J 0
(3300 3125);
DISPLAY 1.021277 (3300 3125);
PAINT ORANGE (3300 3125);
DISPLAY INVISIBLE (3300 3125);
FORCEADD OFFPAGE..2
(2925 2975);
FORCEPROP 2 LAST $XR0 29 
J 0
(3114 2975);
DISPLAY 0.638298 (3114 2975);
PAINT MONO (3114 2975);
FORCEPROP 2 LAST CDS_LIB mstr_standard
J 0
(2925 2975);
DISPLAY 1.340426 (2925 2975);
PAINT MONO (2925 2975);
DISPLAY INVISIBLE (2925 2975);
FORCEPROP 1 LAST OFFPAGE TRUE
J 0
(3250 2850);
DISPLAY 0.829787 (3250 2850);
PAINT GREEN (3250 2850);
DISPLAY INVISIBLE (3250 2850);
FORCEPROP 1 LAST COMMENT_BODY TRUE
J 0
(2880 2880);
DISPLAY 1.170213 (2880 2880);
PAINT PEACH (2880 2880);
DISPLAY INVISIBLE (2880 2880);
FORCEPROP 2 LAST PATH I6
J 0
(3125 3025);
DISPLAY 1.021277 (3125 3025);
PAINT ORANGE (3125 3025);
DISPLAY INVISIBLE (3125 3025);
FORCEADD OFFPAGE..2
(2950 2775);
FORCEPROP 2 LAST $XR0 29 
J 0
(3139 2775);
DISPLAY 0.638298 (3139 2775);
PAINT MONO (3139 2775);
FORCEPROP 2 LAST CDS_LIB mstr_standard
J 0
(2950 2775);
DISPLAY 1.340426 (2950 2775);
PAINT MONO (2950 2775);
DISPLAY INVISIBLE (2950 2775);
FORCEPROP 1 LAST OFFPAGE TRUE
J 0
(3275 2650);
DISPLAY 0.829787 (3275 2650);
PAINT GREEN (3275 2650);
DISPLAY INVISIBLE (3275 2650);
FORCEPROP 1 LAST COMMENT_BODY TRUE
J 0
(2905 2680);
DISPLAY 1.170213 (2905 2680);
PAINT PEACH (2905 2680);
DISPLAY INVISIBLE (2905 2680);
FORCEPROP 2 LAST PATH I7
J 0
(3150 2825);
DISPLAY 1.021277 (3150 2825);
PAINT ORANGE (3150 2825);
DISPLAY INVISIBLE (3150 2825);
FORCEADD OFFPAGE..4
(2925 2825);
FORCEPROP 2 LAST $XR0 29 
J 0
(3141 2825);
DISPLAY 0.638298 (3141 2825);
PAINT MONO (3141 2825);
FORCEPROP 2 LAST CDS_LIB mstr_standard
J 0
(2925 2825);
DISPLAY 1.340426 (2925 2825);
PAINT MONO (2925 2825);
DISPLAY INVISIBLE (2925 2825);
FORCEPROP 1 LAST OFFPAGE TRUE
J 0
(3250 2700);
DISPLAY 0.829787 (3250 2700);
PAINT GREEN (3250 2700);
DISPLAY INVISIBLE (3250 2700);
FORCEPROP 1 LAST COMMENT_BODY TRUE
J 0
(2900 2725);
DISPLAY 1.170213 (2900 2725);
PAINT PEACH (2900 2725);
DISPLAY INVISIBLE (2900 2725);
FORCEPROP 2 LAST PATH I8
J 0
(3150 2875);
DISPLAY 1.021277 (3150 2875);
PAINT ORANGE (3150 2875);
DISPLAY INVISIBLE (3150 2875);
FORCEADD OFFPAGE..3
(2925 2875);
FORCEPROP 2 LAST $XR0 29 
J 0
(3139 2875);
DISPLAY 0.638298 (3139 2875);
PAINT MONO (3139 2875);
FORCEPROP 2 LAST CDS_LIB mstr_standard
J 0
(2925 2875);
DISPLAY 1.340426 (2925 2875);
PAINT MONO (2925 2875);
DISPLAY INVISIBLE (2925 2875);
FORCEPROP 1 LAST OFFPAGE TRUE
J 0
(3250 2750);
DISPLAY 1.170213 (3250 2750);
PAINT GREEN (3250 2750);
DISPLAY INVISIBLE (3250 2750);
FORCEPROP 1 LAST COMMENT_BODY TRUE
J 0
(2875 2775);
DISPLAY 1.170213 (2875 2775);
PAINT GREEN (2875 2775);
DISPLAY INVISIBLE (2875 2775);
FORCEPROP 2 LAST PATH I9
J 0
(3300 2925);
DISPLAY 1.021277 (3300 2925);
PAINT ORANGE (3300 2925);
DISPLAY INVISIBLE (3300 2925);
FORCEADD DESIGN_NOTE..1
(-150 1875);
FORCEPROP 2 LAST CDS_LIB mstr_symbols
J 0
(-150 1875);
PAINT ORANGE (-150 1875);
DISPLAY INVISIBLE (-150 1875);
FORCEPROP 1 LAST COMMENT_BODY TRUE
J 0
(-125 1975);
DISPLAY 0.978723 (-125 1975);
PAINT ORANGE (-125 1975);
DISPLAY INVISIBLE (-125 1975);
FORCEADD INTEL_CORP_BPAGE..1
(4250 200);
FORCEPROP 1 LAST CDS_CON_LAST_MODIFIED Tue Dec 01 11:51:47 2015
J 0
(2825 525);
PAINT ORANGE (2825 525);
DISPLAY INVISIBLE (2825 525);
FORCEPROP 1 LAST CUSTOM_TXT_CDS <CURRENT_DESIGN_SHEET> OF <TOTAL_DESIGN_SHEETS>
J 0
(3750 225);
PAINT GREEN (3750 225);
FORCEPROP 1 LAST CUSTOM_TXT_CDS <CON_LAST_MODIFIED>
J 0
(2325 550);
PAINT GREEN (2325 550);
FORCEPROP 2 LAST CUSTOM_TXT_CDS <XR_PAGE_TITLE>
J 0
(-3640 5450);
DISPLAY 0.638298 (-3640 5450);
PAINT PINK (-3640 5450);
DISPLAY INVISIBLE (-3640 5450);
FORCEPROP 1 LAST SCH_ADDRESS3 Santa Clara, CA 95052-8119
J 0
(275 225);
DISPLAY 0.617021 (275 225);
PAINT GREEN (275 225);
FORCEPROP 1 LAST SCH_ADDRESS2 P.O. BOX 58119
J 0
(275 275);
DISPLAY 0.617021 (275 275);
PAINT GREEN (275 275);
FORCEPROP 1 LAST SCH_ADDRESS1 2200 Mission College Blvd.
J 0
(275 325);
DISPLAY 0.617021 (275 325);
PAINT GREEN (275 325);
FORCEPROP 1 LAST SCH_TITLE HFI-IO CONNECTOR
J 0
(-3700 250);
DISPLAY 1.212766 (-3700 250);
PAINT ORANGE (-3700 250);
FORCEPROP 1 LAST SCH_NUMBER H4694802
J 0
(2950 350);
DISPLAY 1.212766 (2950 350);
PAINT YELLOW (2950 350);
FORCEPROP 1 LAST SCH_DEPT BESD
J 1
(-200 300);
DISPLAY 1.212766 (-200 300);
PAINT YELLOW (-200 300);
FORCEPROP 1 LAST SCH_REV 2.420
J 0
(4000 350);
DISPLAY 0.978723 (4000 350);
PAINT YELLOW (4000 350);
FORCEPROP 2 LAST PAGE_BORDER TRUE
J 0
(-3640 5450);
DISPLAY 0.638298 (-3640 5450);
PAINT PINK (-3640 5450);
DISPLAY INVISIBLE (-3640 5450);
FORCEPROP 2 LAST CDS_LIB mstr_symbols
J 0
(4250 200);
PAINT MONO (4250 200);
DISPLAY INVISIBLE (4250 200);
FORCEPROP 1 LAST COMMENT_BODY TRUE
J 0
(4262 212);
DISPLAY 0.468085 (4262 212);
PAINT GREEN (4262 212);
DISPLAY INVISIBLE (4262 212);
FORCEPROP 2 LAST CDS_XR_PAGE_TITLE CR-91 : @BASEBOARD_FAB2_LIB.BASEBOARD_FAB2(SCH_1):PAGE91
J 0
(-3640 5450);
DISPLAY 0.638298 (-3640 5450);
PAINT PINK (-3640 5450);
DISPLAY INVISIBLE (-3640 5450);
WIRE 16 -1 (-475 3125)(-375 3125);
WIRE 16 -1 (-475 2975)(-475 3125);
WIRE 16 -1 (-375 2975)(-475 2975);
WIRE 16 -1 (-475 2925)(-475 2975);
WIRE 16 -1 (-475 2925)(-375 2925);
WIRE 16 -1 (-475 2775)(-475 2925);
WIRE 16 -1 (-375 2775)(-475 2775);
WIRE 16 -1 (-475 2575)(-475 2775);
WIRE 16 -1 (-375 2575)(-475 2575);
WIRE 16 -1 (-475 2475)(-475 2575);
WIRE 16 -1 (-375 2475)(-475 2475);
WIRE 16 -1 (-475 2375)(-475 2475);
WIRE 16 -1 (-600 3525)(-600 3425);
WIRE 16 -1 (-975 3525)(-600 3525);
WIRE 16 -1 (-975 3425)(-975 3525);
WIRE 16 -1 (-1350 3525)(-975 3525);
WIRE 16 -1 (-1350 3425)(-1350 3525);
WIRE 16 -1 (-1725 3525)(-1350 3525);
WIRE 16 -1 (-1725 3425)(-1725 3525);
WIRE 16 -1 (-1725 3575)(-1725 3525);
WIRE 16 -1 (-375 2625)(-525 2625);
WIRE 16 -1 (-525 2625)(-525 3575);
WIRE 16 -1 (650 3450)(650 3550);
WIRE 16 -1 (650 3550)(900 3550);
WIRE 16 -1 (900 3450)(900 3550);
WIRE 16 -1 (1150 3550)(900 3550);
WIRE 16 -1 (1150 3450)(1150 3550);
WIRE 16 -1 (1400 3550)(1150 3550);
WIRE 16 -1 (1400 3450)(1400 3550);
WIRE 16 -1 (1400 3550)(1650 3550);
WIRE 16 -1 (1650 3450)(1650 3550);
WIRE 16 -1 (1650 3550)(1875 3550);
WIRE 16 -1 (1875 3450)(1875 3550);
WIRE 16 -1 (1875 3550)(2125 3550);
WIRE 16 -1 (2125 3450)(2125 3550);
WIRE 16 -1 (2125 3550)(2400 3550);
WIRE 16 -1 (2400 3625)(2400 3550);
WIRE 16 -1 (2400 3550)(2400 3450);
WIRE 16 -1 (425 2675)(575 2675);
WIRE 16 -1 (575 2675)(575 2725);
WIRE 16 -1 (575 3575)(575 2725);
WIRE 16 -1 (575 2725)(425 2725);
WIRE 16 -1 (525 2375)(525 2475);
WIRE 16 -1 (525 2475)(425 2475);
WIRE 16 -1 (-375 2725)(-2750 2725);
FORCEPROP 0 LAST SIG_NAME TP_HFI_IO_CONN0_RSVD_17
J 0
(-2725 2735);
DISPLAY 0.617021 (-2725 2735);
PAINT ORANGE (-2725 2735);
FORCEPROP 2 LASTPROP $XRERR UNIQUE?
J 0
(-2990 2725);
DISPLAY 0.638298 (-2990 2725);
PAINT MONO (-2990 2725);
DISPLAY INVISIBLE (-2990 2725);
WIRE 16 -1 (-375 2675)(-2750 2675);
FORCEPROP 0 LAST SIG_NAME PWRGD_PVPP_ABC
J 0
(-2725 2685);
DISPLAY 0.617021 (-2725 2685);
PAINT ORANGE (-2725 2685);
WIRE 16 -1 (-1725 3225)(-1725 3075);
WIRE 16 -1 (-375 3075)(-1725 3075);
WIRE 16 -1 (-2750 3075)(-1725 3075);
FORCEPROP 0 LAST SIG_NAME FM_MODPRST_HFI0_CPU0_LVT2_N
J 0
(-2725 3085);
DISPLAY 0.617021 (-2725 3085);
PAINT ORANGE (-2725 3085);
WIRE 16 -1 (-1350 3225)(-1350 3025);
WIRE 16 -1 (-375 3025)(-1350 3025);
WIRE 16 -1 (-2750 3025)(-1350 3025);
FORCEPROP 0 LAST SIG_NAME LED_HFI0_CPU0_N
J 0
(-2725 3035);
DISPLAY 0.617021 (-2725 3035);
PAINT ORANGE (-2725 3035);
WIRE 16 -1 (-375 2875)(-975 2875);
WIRE 16 -1 (-975 3225)(-975 2875);
WIRE 16 -1 (-2750 2875)(-975 2875);
FORCEPROP 2 LAST SIG_NAME FM_MODPRST_HFI1_CPU0_LVT2_N
J 0
(-2725 2885);
DISPLAY 0.617021 (-2725 2885);
PAINT ORANGE (-2725 2885);
WIRE 16 -1 (-375 2825)(-600 2825);
WIRE 16 -1 (-600 3225)(-600 2825);
WIRE 16 -1 (-2750 2825)(-600 2825);
FORCEPROP 0 LAST SIG_NAME LED_HFI1_CPU0_N
J 0
(-2725 2835);
DISPLAY 0.617021 (-2725 2835);
PAINT ORANGE (-2725 2835);
WIRE 16 -1 (1875 3250)(1875 2925);
WIRE 16 -1 (1875 2925)(2875 2925);
FORCEPROP 0 LAST SIG_NAME SMB_HFI1_CPU0_LVC2_SCL
J 0
(2125 2935);
DISPLAY 0.617021 (2125 2935);
PAINT ORANGE (2125 2935);
WIRE 16 -1 (425 2925)(1875 2925);
WIRE 16 -1 (2900 2625)(425 2625);
FORCEPROP 0 LAST SIG_NAME SMB_OCP_FRU_STBY_LVC3_SCL
J 0
(2125 2635);
DISPLAY 0.617021 (2125 2635);
PAINT ORANGE (2125 2635);
WIRE 16 -1 (2900 2575)(425 2575);
FORCEPROP 0 LAST SIG_NAME SMB_OCP_FRU_STBY_LVC3_SDA
J 0
(2125 2585);
DISPLAY 0.617021 (2125 2585);
PAINT ORANGE (2125 2585);
WIRE 16 -1 (1400 3250)(1400 3025);
WIRE 16 -1 (2875 3025)(1400 3025);
FORCEPROP 2 LAST SIG_NAME RST_HFI0_CPU0_LVT2_N
J 0
(2125 3035);
DISPLAY 0.617021 (2125 3035);
PAINT ORANGE (2125 3035);
WIRE 16 -1 (425 3025)(1400 3025);
WIRE 16 -1 (1150 3250)(1150 2975);
WIRE 16 -1 (2875 2975)(1150 2975);
FORCEPROP 0 LAST SIG_NAME IRQ_HFI0_CPU0_LVT2_N
J 0
(2125 2985);
DISPLAY 0.617021 (2125 2985);
PAINT ORANGE (2125 2985);
WIRE 16 -1 (425 2975)(1150 2975);
WIRE 16 -1 (650 3250)(650 2775);
WIRE 16 -1 (2900 2775)(650 2775);
FORCEPROP 0 LAST SIG_NAME IRQ_HFI1_CPU0_LVT2_N
J 0
(2125 2785);
DISPLAY 0.617021 (2125 2785);
PAINT ORANGE (2125 2785);
WIRE 16 -1 (425 2775)(650 2775);
WIRE 16 -1 (900 3250)(900 2825);
WIRE 16 -1 (2875 2825)(900 2825);
FORCEPROP 0 LAST SIG_NAME RST_HFI1_CPU0_LVT2_N
J 0
(2125 2835);
DISPLAY 0.617021 (2125 2835);
PAINT ORANGE (2125 2835);
WIRE 16 -1 (425 2825)(900 2825);
WIRE 16 -1 (1650 3250)(1650 2875);
WIRE 16 -1 (1650 2875)(2875 2875);
FORCEPROP 0 LAST SIG_NAME SMB_HFI1_CPU0_LVC2_SDA
J 0
(2125 2885);
DISPLAY 0.617021 (2125 2885);
PAINT ORANGE (2125 2885);
WIRE 16 -1 (425 2875)(1650 2875);
WIRE 16 -1 (2400 3250)(2400 3125);
WIRE 16 -1 (2400 3125)(2875 3125);
WIRE 16 -1 (425 3125)(2400 3125);
FORCEPROP 0 LAST SIG_NAME SMB_HFI0_CPU0_LVC2_SCL
J 0
(2125 3135);
DISPLAY 0.617021 (2125 3135);
PAINT ORANGE (2125 3135);
WIRE 16 -1 (2125 3250)(2125 3075);
WIRE 16 -1 (2125 3075)(2875 3075);
WIRE 16 -1 (425 3075)(2125 3075);
FORCEPROP 0 LAST SIG_NAME SMB_HFI0_CPU0_LVC2_SDA
J 0
(2125 3085);
DISPLAY 0.617021 (2125 3085);
PAINT ORANGE (2125 3085);
DOT 1 (2125 3075);
DOT 1 (900 2825);
DOT 1 (650 2775);
DOT 1 (-600 2825);
DOT 1 (-1350 3025);
DOT 1 (-1725 3075);
DOT 1 (-1725 3525);
DOT 1 (-975 2875);
DOT 1 (-1350 3525);
DOT 1 (-975 3525);
DOT 1 (-475 2925);
DOT 1 (-475 2775);
DOT 1 (-475 2975);
DOT 1 (575 2725);
DOT 1 (-475 2475);
DOT 1 (900 3550);
DOT 1 (1150 2975);
DOT 1 (1400 3550);
DOT 1 (2400 3550);
DOT 1 (2125 3550);
DOT 1 (1875 3550);
DOT 1 (1650 3550);
DOT 1 (1650 2875);
DOT 1 (2400 3125);
DOT 1 (1150 3550);
DOT 1 (1400 3025);
DOT 1 (1875 2925);
DOT 1 (-475 2575);
FORCENOTE
FRU SMBUS ADDRESS 0XA2
(-350 1750) 0;
DISPLAY LEFT (-350 1750);
DISPLAY 1.021277 (-350 1750);
PAINT PURPLE (-350 1750);
FORCENOTE
TEMP SMBUS ADDRESS 0X3E
(-350 1675) 0;
DISPLAY LEFT (-350 1675);
DISPLAY 1.021277 (-350 1675);
PAINT PURPLE (-350 1675);
FORCENOTE
FOR DEBUG ONLY
(-275 2100) 0;
DISPLAY LEFT (-275 2100);
DISPLAY 1.021277 (-275 2100);
PAINT PURPLE (-275 2100);
FORCENOTE
BOM_COST=PROC_SIDEBAND
(-3625 475) 0;
DISPLAY LEFT (-3625 475);
DISPLAY 1.021277 (-3625 475);
PAINT PURPLE (-3625 475);
FORCENOTE
ROOM=HFI
(-3650 550) 0;
DISPLAY LEFT (-3650 550);
DISPLAY 1.021277 (-3650 550);
PAINT PURPLE (-3650 550);
QUIT
